(kicad_pcb
	(version 20260206)
	(generator "pcbnew")
	(generator_version "10.0")
	(general
		(thickness 1.6)
		(legacy_teardrops no)
	)
	(paper "A4")
	(title_block
		(title "04192023_DAF0TMB3IC0_F0TG_MB_C_brd_V02_OCP.brd")
		(comment 1 "Grand Teton / footprints 6863-6868 of 8354")
	)
	(layers
		(0 "F.Cu" signal "TOP")
		(4 "In1.Cu" signal "GND")
		(6 "In2.Cu" signal "IN1")
		(8 "In3.Cu" signal "GND1")
		(10 "In4.Cu" signal "IN2")
		(12 "In5.Cu" signal "GND2")
		(14 "In6.Cu" signal "IN3")
		(16 "In7.Cu" signal "GND3")
		(18 "In8.Cu" signal "VCC")
		(20 "In9.Cu" signal "VCC1")
		(22 "In10.Cu" signal "GND4")
		(24 "In11.Cu" signal "IN4")
		(26 "In12.Cu" signal "GND5")
		(28 "In13.Cu" signal "IN5")
		(30 "In14.Cu" signal "GND6")
		(32 "In15.Cu" signal "IN6")
		(34 "In16.Cu" signal "GND7")
		(2 "B.Cu" signal "BOTTOM")
		(9 "F.Adhes" user "F.Adhesive")
		(11 "B.Adhes" user "B.Adhesive")
		(13 "F.Paste" user "Package Geometry/Pastemask Top")
		(15 "B.Paste" user "Package Geometry/Pastemask Bottom")
		(5 "F.SilkS" user "Ref Des/Silkscreen Top")
		(7 "B.SilkS" user "Ref Des/Silkscreen Bottom")
		(1 "F.Mask" user "Board Geometry/Soldermask Top")
		(3 "B.Mask" user "Board Geometry/Soldermask Bottom")
		(17 "Dwgs.User" user "User.Drawings")
		(19 "Cmts.User" user "User.Comments")
		(21 "Eco1.User" user "User.Eco1")
		(23 "Eco2.User" user "User.Eco2")
		(25 "Edge.Cuts" user "Board Geometry/Outline")
		(27 "Margin" user)
		(31 "F.CrtYd" user "Package Geometry/Place Bound Top")
		(29 "B.CrtYd" user "Package Geometry/Place Bound Bottom")
		(35 "F.Fab" user "Ref Des/Assembly Top")
		(33 "B.Fab" user "Ref Des/Assembly Bottom")
	)
	(footprint ""
		(layer "B.Cu")
		(at 373.329454 -252.54331)
		(property "Reference" "C2545"
			(at 0 0 0)
			(layer "B.SilkS")
			(hide yes)
			(effects
				(font
					(size 1.27 1.27)
				)
				(justify mirror)
			)
		)
		(property "Value" ""
			(at 0 0 0)
			(layer "B.Fab")
			(effects
				(font
					(size 1.27 1.27)
				)
				(justify mirror)
			)
		)
		(duplicate_pad_numbers_are_jumpers no)
		(fp_line
			(start -0.7874 -0.4064)
			(end -0.7874 0.4064)
			(stroke
				(width 0.1524)
				(type default)
			)
			(layer "B.SilkS")
		)
		(fp_line
			(start -0.7874 0.4064)
			(end 0.7874 0.4064)
			(stroke
				(width 0.1524)
				(type default)
			)
			(layer "B.SilkS")
		)
		(fp_line
			(start 0.7874 -0.4064)
			(end -0.7874 -0.4064)
			(stroke
				(width 0.1524)
				(type default)
			)
			(layer "B.SilkS")
		)
		(fp_line
			(start 0.7874 0.4064)
			(end 0.7874 -0.4064)
			(stroke
				(width 0.1524)
				(type default)
			)
			(layer "B.SilkS")
		)
		(fp_line
			(start -0.67945 -0.3048)
			(end -0.67945 0.3048)
			(stroke
				(width 0.1)
				(type default)
			)
			(layer "B.Fab")
		)
		(fp_line
			(start -0.67945 0.3048)
			(end -0.120396 0.3048)
			(stroke
				(width 0.1)
				(type default)
			)
			(layer "B.Fab")
		)
		(fp_line
			(start -0.12065 -0.3048)
			(end -0.67945 -0.3048)
			(stroke
				(width 0.1)
				(type default)
			)
			(layer "B.Fab")
		)
		(fp_line
			(start -0.12065 -0.2794)
			(end -0.12065 -0.3048)
			(stroke
				(width 0.1)
				(type default)
			)
			(layer "B.Fab")
		)
		(fp_line
			(start -0.120396 0.2794)
			(end 0.12065 0.2794)
			(stroke
				(width 0.1)
				(type default)
			)
			(layer "B.Fab")
		)
		(fp_line
			(start -0.120396 0.3048)
			(end -0.120396 0.2794)
			(stroke
				(width 0.1)
				(type default)
			)
			(layer "B.Fab")
		)
		(fp_line
			(start 0.12065 -0.305054)
			(end 0.12065 -0.2794)
			(stroke
				(width 0.1)
				(type default)
			)
			(layer "B.Fab")
		)
		(fp_line
			(start 0.12065 -0.2794)
			(end -0.12065 -0.2794)
			(stroke
				(width 0.1)
				(type default)
			)
			(layer "B.Fab")
		)
		(fp_line
			(start 0.12065 0.2794)
			(end 0.12065 0.3048)
			(stroke
				(width 0.1)
				(type default)
			)
			(layer "B.Fab")
		)
		(fp_line
			(start 0.12065 0.3048)
			(end 0.67945 0.3048)
			(stroke
				(width 0.1)
				(type default)
			)
			(layer "B.Fab")
		)
		(fp_line
			(start 0.67945 -0.305054)
			(end 0.12065 -0.305054)
			(stroke
				(width 0.1)
				(type default)
			)
			(layer "B.Fab")
		)
		(fp_line
			(start 0.67945 0.3048)
			(end 0.67945 -0.305054)
			(stroke
				(width 0.1)
				(type default)
			)
			(layer "B.Fab")
		)
		(pad "1" smd circle
			(at 0.40005 0 180)
			(size 0 0)
			(layers "B.Cu" "B.Mask" "B.Paste")
			(net "PVDDCR_SOC_P0")
		)
		(pad "2" smd circle
			(at -0.40005 0 180)
			(size 0 0)
			(layers "B.Cu" "B.Mask" "B.Paste")
			(net "GND")
		)
	)
	(footprint ""
		(layer "B.Cu")
		(at 229.576122 -228.143308 90)
		(property "Reference" "R201"
			(at 0 0 90)
			(layer "B.SilkS")
			(hide yes)
			(effects
				(font
					(size 1.27 1.27)
				)
				(justify mirror)
			)
		)
		(property "Value" ""
			(at 0 0 90)
			(layer "B.Fab")
			(effects
				(font
					(size 1.27 1.27)
				)
				(justify mirror)
			)
		)
		(duplicate_pad_numbers_are_jumpers no)
		(fp_line
			(start 0.7874 -0.4064)
			(end -0.7874 -0.4064)
			(stroke
				(width 0.1524)
				(type default)
			)
			(layer "B.SilkS")
		)
		(fp_line
			(start -0.7874 -0.4064)
			(end -0.7874 0.4064)
			(stroke
				(width 0.1524)
				(type default)
			)
			(layer "B.SilkS")
		)
		(fp_line
			(start 0.7874 0.4064)
			(end 0.7874 -0.4064)
			(stroke
				(width 0.1524)
				(type default)
			)
			(layer "B.SilkS")
		)
		(fp_line
			(start -0.7874 0.4064)
			(end 0.7874 0.4064)
			(stroke
				(width 0.1524)
				(type default)
			)
			(layer "B.SilkS")
		)
		(fp_line
			(start 0.67945 -0.305054)
			(end 0.12065 -0.305054)
			(stroke
				(width 0.1)
				(type default)
			)
			(layer "B.Fab")
		)
		(fp_line
			(start 0.12065 -0.305054)
			(end 0.12065 -0.2794)
			(stroke
				(width 0.1)
				(type default)
			)
			(layer "B.Fab")
		)
		(fp_line
			(start -0.12065 -0.3048)
			(end -0.67945 -0.3048)
			(stroke
				(width 0.1)
				(type default)
			)
			(layer "B.Fab")
		)
		(fp_line
			(start -0.67945 -0.3048)
			(end -0.67945 0.3048)
			(stroke
				(width 0.1)
				(type default)
			)
			(layer "B.Fab")
		)
		(fp_line
			(start 0.12065 -0.2794)
			(end -0.12065 -0.2794)
			(stroke
				(width 0.1)
				(type default)
			)
			(layer "B.Fab")
		)
		(fp_line
			(start -0.12065 -0.2794)
			(end -0.12065 -0.3048)
			(stroke
				(width 0.1)
				(type default)
			)
			(layer "B.Fab")
		)
		(fp_line
			(start 0.12065 0.2794)
			(end 0.12065 0.3048)
			(stroke
				(width 0.1)
				(type default)
			)
			(layer "B.Fab")
		)
		(fp_line
			(start -0.120396 0.2794)
			(end 0.12065 0.2794)
			(stroke
				(width 0.1)
				(type default)
			)
			(layer "B.Fab")
		)
		(fp_line
			(start 0.67945 0.3048)
			(end 0.67945 -0.305054)
			(stroke
				(width 0.1)
				(type default)
			)
			(layer "B.Fab")
		)
		(fp_line
			(start 0.12065 0.3048)
			(end 0.67945 0.3048)
			(stroke
				(width 0.1)
				(type default)
			)
			(layer "B.Fab")
		)
		(fp_line
			(start -0.120396 0.3048)
			(end -0.120396 0.2794)
			(stroke
				(width 0.1)
				(type default)
			)
			(layer "B.Fab")
		)
		(fp_line
			(start -0.67945 0.3048)
			(end -0.120396 0.3048)
			(stroke
				(width 0.1)
				(type default)
			)
			(layer "B.Fab")
		)
		(pad "1" smd circle
			(at 0.40005 0 270)
			(size 0 0)
			(layers "B.Cu" "B.Mask" "B.Paste")
			(net "P3V3_AUX")
		)
		(pad "2" smd circle
			(at -0.40005 0 270)
			(size 0 0)
			(layers "B.Cu" "B.Mask" "B.Paste")
			(net "PU_U2_EN")
		)
	)
	(footprint ""
		(layer "B.Cu")
		(at 231.082596 -324.980554)
		(property "Reference" "R1252"
			(at 0 0 0)
			(layer "B.SilkS")
			(hide yes)
			(effects
				(font
					(size 1.27 1.27)
				)
				(justify mirror)
			)
		)
		(property "Value" ""
			(at 0 0 0)
			(layer "B.Fab")
			(effects
				(font
					(size 1.27 1.27)
				)
				(justify mirror)
			)
		)
		(duplicate_pad_numbers_are_jumpers no)
		(fp_line
			(start -0.7874 -0.4064)
			(end -0.7874 0.4064)
			(stroke
				(width 0.1524)
				(type default)
			)
			(layer "B.SilkS")
		)
		(fp_line
			(start -0.7874 0.4064)
			(end 0.7874 0.4064)
			(stroke
				(width 0.1524)
				(type default)
			)
			(layer "B.SilkS")
		)
		(fp_line
			(start 0.7874 -0.4064)
			(end -0.7874 -0.4064)
			(stroke
				(width 0.1524)
				(type default)
			)
			(layer "B.SilkS")
		)
		(fp_line
			(start 0.7874 0.4064)
			(end 0.7874 -0.4064)
			(stroke
				(width 0.1524)
				(type default)
			)
			(layer "B.SilkS")
		)
		(fp_line
			(start -0.67945 -0.3048)
			(end -0.67945 0.3048)
			(stroke
				(width 0.1)
				(type default)
			)
			(layer "B.Fab")
		)
		(fp_line
			(start -0.67945 0.3048)
			(end -0.120396 0.3048)
			(stroke
				(width 0.1)
				(type default)
			)
			(layer "B.Fab")
		)
		(fp_line
			(start -0.12065 -0.3048)
			(end -0.67945 -0.3048)
			(stroke
				(width 0.1)
				(type default)
			)
			(layer "B.Fab")
		)
		(fp_line
			(start -0.12065 -0.2794)
			(end -0.12065 -0.3048)
			(stroke
				(width 0.1)
				(type default)
			)
			(layer "B.Fab")
		)
		(fp_line
			(start -0.120396 0.2794)
			(end 0.12065 0.2794)
			(stroke
				(width 0.1)
				(type default)
			)
			(layer "B.Fab")
		)
		(fp_line
			(start -0.120396 0.3048)
			(end -0.120396 0.2794)
			(stroke
				(width 0.1)
				(type default)
			)
			(layer "B.Fab")
		)
		(fp_line
			(start 0.12065 -0.305054)
			(end 0.12065 -0.2794)
			(stroke
				(width 0.1)
				(type default)
			)
			(layer "B.Fab")
		)
		(fp_line
			(start 0.12065 -0.2794)
			(end -0.12065 -0.2794)
			(stroke
				(width 0.1)
				(type default)
			)
			(layer "B.Fab")
		)
		(fp_line
			(start 0.12065 0.2794)
			(end 0.12065 0.3048)
			(stroke
				(width 0.1)
				(type default)
			)
			(layer "B.Fab")
		)
		(fp_line
			(start 0.12065 0.3048)
			(end 0.67945 0.3048)
			(stroke
				(width 0.1)
				(type default)
			)
			(layer "B.Fab")
		)
		(fp_line
			(start 0.67945 -0.305054)
			(end 0.12065 -0.305054)
			(stroke
				(width 0.1)
				(type default)
			)
			(layer "B.Fab")
		)
		(fp_line
			(start 0.67945 0.3048)
			(end 0.67945 -0.305054)
			(stroke
				(width 0.1)
				(type default)
			)
			(layer "B.Fab")
		)
		(pad "1" smd rect
			(at 0.40005 0)
			(size 0.4572 0.508)
			(layers "B.Cu" "B.Mask" "B.Paste")
			(net "P1V8_CPU0_RT_1D_ADC")
		)
		(pad "2" smd rect
			(at -0.40005 0)
			(size 0.4572 0.508)
			(layers "B.Cu" "B.Mask" "B.Paste")
			(net "P1V8_CPU0_RT_1D_ADC_TIC")
		)
	)
	(footprint ""
		(layer "B.Cu")
		(at 224.310194 -336.846164 180)
		(property "Reference" "U6020"
			(at -1.980438 -5.745734 0)
			(unlocked yes)
			(layer "B.SilkS")
			(effects
				(font
					(size 0.7874 0.5842)
					(thickness 0.1524)
				)
				(justify left mirror)
			)
		)
		(property "Value" ""
			(at 0 0 0)
			(layer "B.Fab")
			(effects
				(font
					(size 1.27 1.27)
				)
				(justify mirror)
			)
		)
		(duplicate_pad_numbers_are_jumpers no)
		(fp_line
			(start 1.8542 3.949954)
			(end -1.8542 3.949954)
			(stroke
				(width 0.1524)
				(type default)
			)
			(layer "B.SilkS")
		)
		(fp_line
			(start 1.8542 -3.949954)
			(end 1.8542 3.949954)
			(stroke
				(width 0.1524)
				(type default)
			)
			(layer "B.SilkS")
		)
		(fp_line
			(start 1.282954 -3.949954)
			(end 1.8542 -3.949954)
			(stroke
				(width 0.1524)
				(type default)
			)
			(layer "B.SilkS")
		)
		(fp_line
			(start 0 -2.667)
			(end 1.282954 -3.949954)
			(stroke
				(width 0.1524)
				(type default)
			)
			(layer "B.SilkS")
		)
		(fp_line
			(start -1.282954 -3.949954)
			(end 0 -2.667)
			(stroke
				(width 0.1524)
				(type default)
			)
			(layer "B.SilkS")
		)
		(fp_line
			(start -1.8542 3.949954)
			(end -1.8542 -3.949954)
			(stroke
				(width 0.1524)
				(type default)
			)
			(layer "B.SilkS")
		)
		(fp_line
			(start -1.8542 -3.949954)
			(end -1.282954 -3.949954)
			(stroke
				(width 0.1524)
				(type default)
			)
			(layer "B.SilkS")
		)
		(fp_poly
			(pts
				(xy 2.737358 -5.05968) (xy 3.753358 -5.05968) (xy 3.245358 -4.04368)
			)
			(stroke
				(width 0)
				(type default)
			)
			(fill yes)
			(layer "B.SilkS")
		)
		(fp_line
			(start 2.249932 3.949954)
			(end -2.249932 3.949954)
			(stroke
				(width 0.1)
				(type default)
			)
			(layer "B.Fab")
		)
		(fp_line
			(start 2.249932 -3.949954)
			(end 2.249932 3.949954)
			(stroke
				(width 0.1)
				(type default)
			)
			(layer "B.Fab")
		)
		(fp_line
			(start -2.249932 3.949954)
			(end -2.249932 -3.949954)
			(stroke
				(width 0.1)
				(type default)
			)
			(layer "B.Fab")
		)
		(fp_line
			(start -2.249932 -3.949954)
			(end 2.249932 -3.949954)
			(stroke
				(width 0.1)
				(type default)
			)
			(layer "B.Fab")
		)
		(fp_poly
			(pts
				(xy 4.8006 -4.08305) (xy 4.8006 -3.06705) (xy 3.7846 -3.57505)
			)
			(stroke
				(width 0)
				(type default)
			)
			(fill yes)
			(layer "B.Fab")
		)
		(pad "1" smd rect
			(at 2.800096 -3.57505 90)
			(size 0.3048 1.6002)
			(layers "B.Cu" "B.Mask" "B.Paste")
			(net "RT_SMB_MUX_ADDR0")
		)
		(pad "2" smd rect
			(at 2.800096 -2.925064 90)
			(size 0.3048 1.6002)
			(layers "B.Cu" "B.Mask" "B.Paste")
			(net "RT_SMB_MUX_ADDR1")
		)
		(pad "3" smd rect
			(at 2.800096 -2.275078 90)
			(size 0.3048 1.6002)
			(layers "B.Cu" "B.Mask" "B.Paste")
			(net "RST_SMB_RT_N")
		)
		(pad "4" smd rect
			(at 2.800096 -1.625092 90)
			(size 0.3048 1.6002)
			(layers "B.Cu" "B.Mask" "B.Paste")
			(net "SMB_RT_CPU1_P0_SDA")
		)
		(pad "5" smd rect
			(at 2.800096 -0.975106 90)
			(size 0.3048 1.6002)
			(layers "B.Cu" "B.Mask" "B.Paste")
			(net "SMB_RT_CPU1_P0_SCL")
		)
		(pad "6" smd rect
			(at 2.800096 -0.32512 90)
			(size 0.3048 1.6002)
			(layers "B.Cu" "B.Mask" "B.Paste")
			(net "SMB_RT_CPU1_P1_SDA")
		)
		(pad "7" smd rect
			(at 2.800096 0.32512 90)
			(size 0.3048 1.6002)
			(layers "B.Cu" "B.Mask" "B.Paste")
			(net "SMB_RT_CPU1_P1_SCL")
		)
		(pad "8" smd rect
			(at 2.800096 0.975106 90)
			(size 0.3048 1.6002)
			(layers "B.Cu" "B.Mask" "B.Paste")
			(net "SMB_RT_CPU1_P3_SDA")
		)
		(pad "9" smd rect
			(at 2.800096 1.625092 90)
			(size 0.3048 1.6002)
			(layers "B.Cu" "B.Mask" "B.Paste")
			(net "SMB_RT_CPU1_P3_SCL")
		)
		(pad "10" smd rect
			(at 2.800096 2.275078 90)
			(size 0.3048 1.6002)
			(layers "B.Cu" "B.Mask" "B.Paste")
			(net "SMB_RT_CPU1_P2_SDA")
		)
		(pad "11" smd rect
			(at 2.800096 2.925064 90)
			(size 0.3048 1.6002)
			(layers "B.Cu" "B.Mask" "B.Paste")
			(net "SMB_RT_CPU1_P2_SCL")
		)
		(pad "12" smd rect
			(at 2.800096 3.57505 90)
			(size 0.3048 1.6002)
			(layers "B.Cu" "B.Mask" "B.Paste")
			(net "GND")
		)
		(pad "13" smd rect
			(at -2.800096 3.57505 90)
			(size 0.3048 1.6002)
			(layers "B.Cu" "B.Mask" "B.Paste")
			(net "SMB_RT_CPU0_P0_SDA")
		)
		(pad "14" smd rect
			(at -2.800096 2.925064 90)
			(size 0.3048 1.6002)
			(layers "B.Cu" "B.Mask" "B.Paste")
			(net "SMB_RT_CPU0_P0_SCL")
		)
		(pad "15" smd rect
			(at -2.800096 2.275078 90)
			(size 0.3048 1.6002)
			(layers "B.Cu" "B.Mask" "B.Paste")
			(net "SMB_RT_CPU0_P1_SDA")
		)
		(pad "16" smd rect
			(at -2.800096 1.625092 90)
			(size 0.3048 1.6002)
			(layers "B.Cu" "B.Mask" "B.Paste")
			(net "SMB_RT_CPU0_P1_SCL")
		)
		(pad "17" smd rect
			(at -2.800096 0.975106 90)
			(size 0.3048 1.6002)
			(layers "B.Cu" "B.Mask" "B.Paste")
			(net "SMB_RT_CPU0_P3_SDA")
		)
		(pad "18" smd rect
			(at -2.800096 0.32512 90)
			(size 0.3048 1.6002)
			(layers "B.Cu" "B.Mask" "B.Paste")
			(net "SMB_RT_CPU0_P3_SCL")
		)
		(pad "19" smd rect
			(at -2.800096 -0.32512 90)
			(size 0.3048 1.6002)
			(layers "B.Cu" "B.Mask" "B.Paste")
			(net "SMB_RT_CPU0_P2_SDA")
		)
		(pad "20" smd rect
			(at -2.800096 -0.975106 90)
			(size 0.3048 1.6002)
			(layers "B.Cu" "B.Mask" "B.Paste")
			(net "SMB_RT_CPU0_P2_SCL")
		)
		(pad "21" smd rect
			(at -2.800096 -1.625092 90)
			(size 0.3048 1.6002)
			(layers "B.Cu" "B.Mask" "B.Paste")
			(net "RT_SMB_MUX_ADDR2")
		)
		(pad "22" smd rect
			(at -2.800096 -2.275078 90)
			(size 0.3048 1.6002)
			(layers "B.Cu" "B.Mask" "B.Paste")
			(net "SMB_MUX_RT_SCL")
		)
		(pad "23" smd rect
			(at -2.800096 -2.925064 90)
			(size 0.3048 1.6002)
			(layers "B.Cu" "B.Mask" "B.Paste")
			(net "SMB_MUX_RT_SDA")
		)
		(pad "24" smd rect
			(at -2.800096 -3.57505 90)
			(size 0.3048 1.6002)
			(layers "B.Cu" "B.Mask" "B.Paste")
			(net "P1V8_AUX")
		)
	)
	(footprint ""
		(layer "B.Cu")
		(at 94.446344 -388.011162 -90)
		(property "Reference" "C350"
			(at 0 0 90)
			(layer "B.SilkS")
			(hide yes)
			(effects
				(font
					(size 1.27 1.27)
				)
				(justify mirror)
			)
		)
		(property "Value" ""
			(at 0 0 90)
			(layer "B.Fab")
			(effects
				(font
					(size 1.27 1.27)
				)
				(justify mirror)
			)
		)
		(duplicate_pad_numbers_are_jumpers no)
		(fp_line
			(start -0.299974 0.150114)
			(end 0.299974 0.150114)
			(stroke
				(width 0.1)
				(type default)
			)
			(layer "B.Fab")
		)
		(fp_line
			(start 0.299974 0.150114)
			(end 0.299974 -0.150114)
			(stroke
				(width 0.1)
				(type default)
			)
			(layer "B.Fab")
		)
		(fp_line
			(start -0.299974 -0.150114)
			(end -0.299974 0.150114)
			(stroke
				(width 0.1)
				(type default)
			)
			(layer "B.Fab")
		)
		(fp_line
			(start 0.299974 -0.150114)
			(end -0.299974 -0.150114)
			(stroke
				(width 0.1)
				(type default)
			)
			(layer "B.Fab")
		)
		(pad "1" smd rect
			(at 0.2667 0 90)
			(size 0.3048 0.381)
			(layers "B.Cu" "B.Mask" "B.Paste")
			(net "P0V9_CPU1_RT1_2A")
		)
		(pad "2" smd rect
			(at -0.2667 0 90)
			(size 0.3048 0.381)
			(layers "B.Cu" "B.Mask" "B.Paste")
			(net "GND")
		)
	)
	(footprint ""
		(layer "B.Cu")
		(at 86.973664 -408.517344 90)
		(property "Reference" "C6685"
			(at 0 0 90)
			(layer "B.SilkS")
			(hide yes)
			(effects
				(font
					(size 1.27 1.27)
				)
				(justify mirror)
			)
		)
		(property "Value" ""
			(at 0 0 90)
			(layer "B.Fab")
			(effects
				(font
					(size 1.27 1.27)
				)
				(justify mirror)
			)
		)
		(duplicate_pad_numbers_are_jumpers no)
		(fp_line
			(start 0.299974 -0.150114)
			(end -0.299974 -0.150114)
			(stroke
				(width 0.1)
				(type default)
			)
			(layer "B.Fab")
		)
		(fp_line
			(start -0.299974 -0.150114)
			(end -0.299974 0.150114)
			(stroke
				(width 0.1)
				(type default)
			)
			(layer "B.Fab")
		)
		(fp_line
			(start 0.299974 0.150114)
			(end 0.299974 -0.150114)
			(stroke
				(width 0.1)
				(type default)
			)
			(layer "B.Fab")
		)
		(fp_line
			(start -0.299974 0.150114)
			(end 0.299974 0.150114)
			(stroke
				(width 0.1)
				(type default)
			)
			(layer "B.Fab")
		)
		(pad "1" smd rect
			(at 0.2667 0 270)
			(size 0.3048 0.381)
			(layers "B.Cu" "B.Mask" "B.Paste")
			(net "P5E_CPU1_P1_TX_BUF_C_DP<12>")
		)
		(pad "2" smd rect
			(at -0.2667 0 270)
			(size 0.3048 0.381)
			(layers "B.Cu" "B.Mask" "B.Paste")
			(net "P5E_CPU1_P1_TX_BUF_DP<12>")
		)
	)
)
